(kicad_pcb
	(version 20260206)
	(generator "pcbnew")
	(generator_version "10.0")
	(general
		(thickness 1.6)
		(legacy_teardrops no)
	)
	(paper "A4")
	(title_block
		(title "Bryce Canyon_R.DPB_16317-1_OCP.brd")
		(comment 1 "Bryce Canyon / footprints 1668-1675 of 2099")
	)
	(layers
		(0 "F.Cu" signal "TOP")
		(4 "In1.Cu" signal "L2GND")
		(6 "In2.Cu" signal "L3")
		(8 "In3.Cu" signal "L4VCC")
		(10 "In4.Cu" signal "L5VCC")
		(12 "In5.Cu" signal "L6")
		(14 "In6.Cu" signal "L7GND")
		(2 "B.Cu" signal "BOTTOM")
		(9 "F.Adhes" user "F.Adhesive")
		(11 "B.Adhes" user "B.Adhesive")
		(13 "F.Paste" user "Package Geometry/Pastemask Top")
		(15 "B.Paste" user "Package Geometry/Pastemask Bottom")
		(5 "F.SilkS" user "Ref Des/Silkscreen Top")
		(7 "B.SilkS" user "Ref Des/Silkscreen Bottom")
		(1 "F.Mask" user "Board Geometry/Soldermask Top")
		(3 "B.Mask" user "Board Geometry/Soldermask Bottom")
		(17 "Dwgs.User" user "User.Drawings")
		(19 "Cmts.User" user "User.Comments")
		(21 "Eco1.User" user "User.Eco1")
		(23 "Eco2.User" user "User.Eco2")
		(25 "Edge.Cuts" user "Board Geometry/Outline")
		(27 "Margin" user)
		(31 "F.CrtYd" user "Package Geometry/Place Bound Top")
		(29 "B.CrtYd" user "Package Geometry/Place Bound Bottom")
		(35 "F.Fab" user "Ref Des/Assembly Top")
		(33 "B.Fab" user "Ref Des/Assembly Bottom")
	)
	(footprint ""
		(layer "F.Cu")
		(at 43.2054 -7.4168 -90)
		(property "Reference" "R121"
			(at 0 0 270)
			(layer "F.SilkS")
			(hide yes)
			(effects
				(font
					(size 1.27 1.27)
				)
			)
		)
		(property "Value" "4K7R2F-GP"
			(at 0.064008 -3.993896 270)
			(unlocked yes)
			(layer "F.Fab")
			(hide yes)
			(effects
				(font
					(size 1.016 1.016)
					(thickness 0.1524)
				)
			)
		)
		(property "Device Type" "R402H16"
			(at 0.064008 -5.517896 270)
			(unlocked yes)
			(layer "F.Fab")
			(hide yes)
			(effects
				(font
					(size 1.016 1.016)
					(thickness 0.1524)
				)
			)
		)
		(duplicate_pad_numbers_are_jumpers no)
		(fp_line
			(start -0.508 -0.9398)
			(end -0.508 0.9398)
			(stroke
				(width 0.1524)
				(type default)
			)
			(layer "F.SilkS")
		)
		(fp_line
			(start 0.508 -0.9398)
			(end -0.508 -0.9398)
			(stroke
				(width 0.1524)
				(type default)
			)
			(layer "F.SilkS")
		)
		(fp_rect
			(start -0.508 0.9398)
			(end 0.508 -0.9398)
			(stroke
				(width 0)
				(type default)
			)
			(fill no)
			(layer "F.CrtYd")
		)
		(fp_rect
			(start -0.508 0.9398)
			(end 0.508 -0.9398)
			(stroke
				(width 0)
				(type default)
			)
			(fill no)
			(layer "F.Fab")
		)
		(pad "1" smd custom
			(at 0 -0.4445 270)
			(size 0.1397 0.1397)
			(layers "F.Cu" "F.Mask" "F.Paste")
			(net "P3V3_STBY_A")
			(options
				(clearance outline)
				(anchor circle)
			)
			(primitives
				(gr_poly
					(pts
						(arc
							(start -0.1778 -0.2794)
							(mid -0.249642 -0.249642)
							(end -0.2794 -0.1778)
						)
						(arc
							(start -0.2794 0.1778)
							(mid -0.249642 0.249642)
							(end -0.1778 0.2794)
						)
						(arc
							(start 0.1778 0.2794)
							(mid 0.249642 0.249642)
							(end 0.2794 0.1778)
						)
						(arc
							(start 0.2794 -0.1778)
							(mid 0.249642 -0.249642)
							(end 0.1778 -0.2794)
						)
					)
					(width 0)
					(fill yes)
				)
			)
		)
		(pad "2" smd custom
			(at 0 0.4445 270)
			(size 0.1397 0.1397)
			(layers "F.Cu" "F.Mask" "F.Paste")
			(net "TEMP1_A0")
			(options
				(clearance outline)
				(anchor circle)
			)
			(primitives
				(gr_poly
					(pts
						(arc
							(start -0.1778 -0.2794)
							(mid -0.249642 -0.249642)
							(end -0.2794 -0.1778)
						)
						(arc
							(start -0.2794 0.1778)
							(mid -0.249642 0.249642)
							(end -0.1778 0.2794)
						)
						(arc
							(start 0.1778 0.2794)
							(mid 0.249642 0.249642)
							(end 0.2794 0.1778)
						)
						(arc
							(start 0.2794 -0.1778)
							(mid 0.249642 -0.249642)
							(end 0.1778 -0.2794)
						)
					)
					(width 0)
					(fill yes)
				)
			)
		)
	)
	(footprint ""
		(layer "F.Cu")
		(at 64.013334 -245.219474 90)
		(property "Reference" "C41"
			(at 0 0 90)
			(layer "F.SilkS")
			(hide yes)
			(effects
				(font
					(size 1.27 1.27)
				)
			)
		)
		(property "Value" "SCD01U16V1KX-GP"
			(at -2.8321 -1.7399 90)
			(unlocked yes)
			(layer "F.Fab")
			(hide yes)
			(effects
				(font
					(size 1.016 1.016)
					(thickness 0.1524)
				)
			)
		)
		(property "Device Type" "C0201H13"
			(at -2.8321 -3.2639 90)
			(unlocked yes)
			(layer "F.Fab")
			(hide yes)
			(effects
				(font
					(size 1.016 1.016)
					(thickness 0.1524)
				)
			)
		)
		(duplicate_pad_numbers_are_jumpers no)
		(fp_rect
			(start -0.2794 0.6477)
			(end 0.2794 -0.6477)
			(stroke
				(width 0)
				(type default)
			)
			(fill no)
			(layer "F.CrtYd")
		)
		(fp_rect
			(start -0.2794 0.6477)
			(end 0.2794 -0.6477)
			(stroke
				(width 0)
				(type default)
			)
			(fill no)
			(layer "F.Fab")
		)
		(pad "1" smd custom
			(at 0 -0.2794 90)
			(size 0.0762 0.0762)
			(layers "F.Cu" "F.Mask" "F.Paste")
			(net "SAS_HDD_RX_N1")
			(options
				(clearance outline)
				(anchor circle)
			)
			(primitives
				(gr_poly
					(pts
						(arc
							(start 0.1524 -0.127)
							(mid 0.137521 -0.162921)
							(end 0.1016 -0.1778)
						)
						(arc
							(start -0.1016 -0.1778)
							(mid -0.137521 -0.162921)
							(end -0.1524 -0.127)
						)
						(arc
							(start -0.1524 0.127)
							(mid -0.137521 0.162921)
							(end -0.1016 0.1778)
						)
						(arc
							(start 0.1016 0.1778)
							(mid 0.137521 0.162921)
							(end 0.1524 0.127)
						)
					)
					(width 0)
					(fill yes)
				)
			)
		)
		(pad "2" smd custom
			(at 0 0.2794 90)
			(size 0.0762 0.0762)
			(layers "F.Cu" "F.Mask" "F.Paste")
			(net "PHY_SCC_B_TO_DRV_B_1_DN")
			(options
				(clearance outline)
				(anchor circle)
			)
			(primitives
				(gr_poly
					(pts
						(arc
							(start 0.1524 -0.127)
							(mid 0.137521 -0.162921)
							(end 0.1016 -0.1778)
						)
						(arc
							(start -0.1016 -0.1778)
							(mid -0.137521 -0.162921)
							(end -0.1524 -0.127)
						)
						(arc
							(start -0.1524 0.127)
							(mid -0.137521 0.162921)
							(end -0.1016 0.1778)
						)
						(arc
							(start 0.1016 0.1778)
							(mid 0.137521 0.162921)
							(end 0.1524 0.127)
						)
					)
					(width 0)
					(fill yes)
				)
			)
		)
	)
	(footprint ""
		(layer "F.Cu")
		(at 52.27955 -102.351586 -90)
		(property "Reference" "R365"
			(at 0 0 270)
			(layer "F.SilkS")
			(hide yes)
			(effects
				(font
					(size 1.27 1.27)
				)
			)
		)
		(property "Value" "4K7R2F-GP"
			(at 0.064008 -3.993896 270)
			(unlocked yes)
			(layer "F.Fab")
			(hide yes)
			(effects
				(font
					(size 1.016 1.016)
					(thickness 0.1524)
				)
			)
		)
		(property "Device Type" "R402H16"
			(at 0.064008 -5.517896 270)
			(unlocked yes)
			(layer "F.Fab")
			(hide yes)
			(effects
				(font
					(size 1.016 1.016)
					(thickness 0.1524)
				)
			)
		)
		(duplicate_pad_numbers_are_jumpers no)
		(fp_line
			(start -0.508 -0.9398)
			(end -0.508 0.9398)
			(stroke
				(width 0.1524)
				(type default)
			)
			(layer "F.SilkS")
		)
		(fp_line
			(start 0.508 -0.9398)
			(end -0.508 -0.9398)
			(stroke
				(width 0.1524)
				(type default)
			)
			(layer "F.SilkS")
		)
		(fp_rect
			(start -0.508 0.9398)
			(end 0.508 -0.9398)
			(stroke
				(width 0)
				(type default)
			)
			(fill no)
			(layer "F.CrtYd")
		)
		(fp_rect
			(start -0.508 0.9398)
			(end 0.508 -0.9398)
			(stroke
				(width 0)
				(type default)
			)
			(fill no)
			(layer "F.Fab")
		)
		(pad "1" smd custom
			(at 0 -0.4445 270)
			(size 0.1397 0.1397)
			(layers "F.Cu" "F.Mask" "F.Paste")
			(net "DRIVE_B_13_FLT_LED")
			(options
				(clearance outline)
				(anchor circle)
			)
			(primitives
				(gr_poly
					(pts
						(arc
							(start -0.1778 -0.2794)
							(mid -0.249642 -0.249642)
							(end -0.2794 -0.1778)
						)
						(arc
							(start -0.2794 0.1778)
							(mid -0.249642 0.249642)
							(end -0.1778 0.2794)
						)
						(arc
							(start 0.1778 0.2794)
							(mid 0.249642 0.249642)
							(end 0.2794 0.1778)
						)
						(arc
							(start 0.2794 -0.1778)
							(mid 0.249642 -0.249642)
							(end 0.1778 -0.2794)
						)
					)
					(width 0)
					(fill yes)
				)
			)
		)
		(pad "2" smd custom
			(at 0 0.4445 270)
			(size 0.1397 0.1397)
			(layers "F.Cu" "F.Mask" "F.Paste")
			(net "GND")
			(options
				(clearance outline)
				(anchor circle)
			)
			(primitives
				(gr_poly
					(pts
						(arc
							(start -0.1778 -0.2794)
							(mid -0.249642 -0.249642)
							(end -0.2794 -0.1778)
						)
						(arc
							(start -0.2794 0.1778)
							(mid -0.249642 0.249642)
							(end -0.1778 0.2794)
						)
						(arc
							(start 0.1778 0.2794)
							(mid 0.249642 0.249642)
							(end 0.2794 0.1778)
						)
						(arc
							(start 0.2794 -0.1778)
							(mid 0.249642 -0.249642)
							(end 0.1778 -0.2794)
						)
					)
					(width 0)
					(fill yes)
				)
			)
		)
	)
	(footprint ""
		(layer "F.Cu")
		(at 463.047588 -229.5017 -90)
		(property "Reference" "R1140"
			(at 0 0 270)
			(layer "F.SilkS")
			(hide yes)
			(effects
				(font
					(size 1.27 1.27)
				)
			)
		)
		(property "Value" "10KR2F-2-GP"
			(at 0.064008 -3.993896 270)
			(unlocked yes)
			(layer "F.Fab")
			(hide yes)
			(effects
				(font
					(size 1.016 1.016)
					(thickness 0.1524)
				)
			)
		)
		(property "Device Type" "R402H16"
			(at 0.064008 -5.517896 270)
			(unlocked yes)
			(layer "F.Fab")
			(hide yes)
			(effects
				(font
					(size 1.016 1.016)
					(thickness 0.1524)
				)
			)
		)
		(duplicate_pad_numbers_are_jumpers no)
		(fp_line
			(start -0.508 -0.9398)
			(end -0.508 0.9398)
			(stroke
				(width 0.1524)
				(type default)
			)
			(layer "F.SilkS")
		)
		(fp_line
			(start 0.508 -0.9398)
			(end -0.508 -0.9398)
			(stroke
				(width 0.1524)
				(type default)
			)
			(layer "F.SilkS")
		)
		(fp_rect
			(start -0.508 0.9398)
			(end 0.508 -0.9398)
			(stroke
				(width 0)
				(type default)
			)
			(fill no)
			(layer "F.CrtYd")
		)
		(fp_rect
			(start -0.508 0.9398)
			(end 0.508 -0.9398)
			(stroke
				(width 0)
				(type default)
			)
			(fill no)
			(layer "F.Fab")
		)
		(pad "1" smd custom
			(at 0 -0.4445 270)
			(size 0.1397 0.1397)
			(layers "F.Cu" "F.Mask" "F.Paste")
			(net "P5V_B_3")
			(options
				(clearance outline)
				(anchor circle)
			)
			(primitives
				(gr_poly
					(pts
						(arc
							(start -0.1778 -0.2794)
							(mid -0.249642 -0.249642)
							(end -0.2794 -0.1778)
						)
						(arc
							(start -0.2794 0.1778)
							(mid -0.249642 0.249642)
							(end -0.1778 0.2794)
						)
						(arc
							(start 0.1778 0.2794)
							(mid 0.249642 0.249642)
							(end 0.2794 0.1778)
						)
						(arc
							(start 0.2794 -0.1778)
							(mid 0.249642 -0.249642)
							(end 0.1778 -0.2794)
						)
					)
					(width 0)
					(fill yes)
				)
			)
		)
		(pad "2" smd custom
			(at 0 0.4445 270)
			(size 0.1397 0.1397)
			(layers "F.Cu" "F.Mask" "F.Paste")
			(net "P5V_B_3_PGOOD")
			(options
				(clearance outline)
				(anchor circle)
			)
			(primitives
				(gr_poly
					(pts
						(arc
							(start -0.1778 -0.2794)
							(mid -0.249642 -0.249642)
							(end -0.2794 -0.1778)
						)
						(arc
							(start -0.2794 0.1778)
							(mid -0.249642 0.249642)
							(end -0.1778 0.2794)
						)
						(arc
							(start 0.1778 0.2794)
							(mid 0.249642 0.249642)
							(end 0.2794 0.1778)
						)
						(arc
							(start 0.2794 -0.1778)
							(mid 0.249642 -0.249642)
							(end 0.1778 -0.2794)
						)
					)
					(width 0)
					(fill yes)
				)
			)
		)
	)
	(footprint ""
		(layer "F.Cu")
		(at 65.83553 -14.990826 90)
		(property "Reference" "VIA51"
			(at 0 0 90)
			(layer "F.SilkS")
			(hide yes)
			(effects
				(font
					(size 1.27 1.27)
				)
			)
		)
		(property "Value" "100OHM-8L-2D36MM-L18-GP"
			(at 3.8989 0.5715 90)
			(unlocked yes)
			(layer "F.Fab")
			(hide yes)
			(effects
				(font
					(size 1.016 1.016)
					(thickness 0.1524)
				)
			)
		)
		(property "Device Type" "VIA-PCIE-4P-414097"
			(at 3.8989 -0.9525 90)
			(unlocked yes)
			(layer "F.Fab")
			(hide yes)
			(effects
				(font
					(size 1.016 1.016)
					(thickness 0.1524)
				)
			)
		)
		(duplicate_pad_numbers_are_jumpers no)
		(fp_rect
			(start -2.0701 0.4826)
			(end 2.0701 -0.4826)
			(stroke
				(width 0)
				(type default)
			)
			(fill no)
			(layer "F.CrtYd")
		)
		(fp_rect
			(start -2.0701 0.4826)
			(end 2.0701 -0.4826)
			(stroke
				(width 0)
				(type default)
			)
			(fill no)
			(layer "F.Fab")
		)
		(pad "1" thru_hole circle
			(at -1.5875 0 90)
			(size 0.508 0.508)
			(drill 0.254)
			(layers "*.Cu" "*.Mask")
			(remove_unused_layers no)
			(net "GND")
			(clearance 0.2286)
			(thermal_gap 0.2286)
		)
		(pad "2" thru_hole circle
			(at -0.5715 0 90)
			(size 0.508 0.508)
			(drill 0.254)
			(layers "*.Cu" "*.Mask")
			(remove_unused_layers no)
			(net "PHY_SCC_B_TO_DRV_B_25_DP")
			(clearance 0.2286)
			(thermal_gap 0.2286)
		)
		(pad "3" thru_hole circle
			(at 0.5715 0 90)
			(size 0.508 0.508)
			(drill 0.254)
			(layers "*.Cu" "*.Mask")
			(remove_unused_layers no)
			(net "PHY_SCC_B_TO_DRV_B_25_DN")
			(clearance 0.2286)
			(thermal_gap 0.2286)
		)
		(pad "4" thru_hole circle
			(at 1.5875 0 90)
			(size 0.508 0.508)
			(drill 0.254)
			(layers "*.Cu" "*.Mask")
			(remove_unused_layers no)
			(net "GND")
			(clearance 0.2286)
			(thermal_gap 0.2286)
		)
	)
	(footprint ""
		(layer "F.Cu")
		(at 314.0964 -340.812882 180)
		(property "Reference" "R105"
			(at 0 0 180)
			(layer "F.SilkS")
			(hide yes)
			(effects
				(font
					(size 1.27 1.27)
				)
			)
		)
		(property "Value" "4K7R2F-GP"
			(at 0.064008 -3.993896 180)
			(unlocked yes)
			(layer "F.Fab")
			(hide yes)
			(effects
				(font
					(size 1.016 1.016)
					(thickness 0.1524)
				)
			)
		)
		(property "Device Type" "R402H16"
			(at 0.064008 -5.517896 180)
			(unlocked yes)
			(layer "F.Fab")
			(hide yes)
			(effects
				(font
					(size 1.016 1.016)
					(thickness 0.1524)
				)
			)
		)
		(duplicate_pad_numbers_are_jumpers no)
		(fp_line
			(start 0.508 -0.9398)
			(end -0.508 -0.9398)
			(stroke
				(width 0.1524)
				(type default)
			)
			(layer "F.SilkS")
		)
		(fp_line
			(start -0.508 -0.9398)
			(end -0.508 0.9398)
			(stroke
				(width 0.1524)
				(type default)
			)
			(layer "F.SilkS")
		)
		(fp_rect
			(start -0.508 0.9398)
			(end 0.508 -0.9398)
			(stroke
				(width 0)
				(type default)
			)
			(fill no)
			(layer "F.CrtYd")
		)
		(fp_rect
			(start -0.508 0.9398)
			(end 0.508 -0.9398)
			(stroke
				(width 0)
				(type default)
			)
			(fill no)
			(layer "F.Fab")
		)
		(pad "1" smd custom
			(at 0 -0.4445 180)
			(size 0.1397 0.1397)
			(layers "F.Cu" "F.Mask" "F.Paste")
			(net "PWM_CAMP_SEL2")
			(options
				(clearance outline)
				(anchor circle)
			)
			(primitives
				(gr_poly
					(pts
						(arc
							(start -0.1778 -0.2794)
							(mid -0.249642 -0.249642)
							(end -0.2794 -0.1778)
						)
						(arc
							(start -0.2794 0.1778)
							(mid -0.249642 0.249642)
							(end -0.1778 0.2794)
						)
						(arc
							(start 0.1778 0.2794)
							(mid 0.249642 0.249642)
							(end 0.2794 0.1778)
						)
						(arc
							(start 0.2794 -0.1778)
							(mid 0.249642 -0.249642)
							(end 0.1778 -0.2794)
						)
					)
					(width 0)
					(fill yes)
				)
			)
		)
		(pad "2" smd custom
			(at 0 0.4445 180)
			(size 0.1397 0.1397)
			(layers "F.Cu" "F.Mask" "F.Paste")
			(net "GND")
			(options
				(clearance outline)
				(anchor circle)
			)
			(primitives
				(gr_poly
					(pts
						(arc
							(start -0.1778 -0.2794)
							(mid -0.249642 -0.249642)
							(end -0.2794 -0.1778)
						)
						(arc
							(start -0.2794 0.1778)
							(mid -0.249642 0.249642)
							(end -0.1778 0.2794)
						)
						(arc
							(start 0.1778 0.2794)
							(mid 0.249642 0.249642)
							(end 0.2794 0.1778)
						)
						(arc
							(start 0.2794 -0.1778)
							(mid 0.249642 -0.249642)
							(end 0.1778 -0.2794)
						)
					)
					(width 0)
					(fill yes)
				)
			)
		)
	)
	(footprint ""
		(layer "F.Cu")
		(at 319.786 -128.627124 180)
		(property "Reference" "VIA37"
			(at 0 0 180)
			(layer "F.SilkS")
			(hide yes)
			(effects
				(font
					(size 1.27 1.27)
				)
			)
		)
		(property "Value" "100OHM-8L-2D36MM-L18-GP"
			(at 3.8989 0.5715 180)
			(unlocked yes)
			(layer "F.Fab")
			(hide yes)
			(effects
				(font
					(size 1.016 1.016)
					(thickness 0.1524)
				)
			)
		)
		(property "Device Type" "VIA-PCIE-4P-414097"
			(at 3.8989 -0.9525 180)
			(unlocked yes)
			(layer "F.Fab")
			(hide yes)
			(effects
				(font
					(size 1.016 1.016)
					(thickness 0.1524)
				)
			)
		)
		(duplicate_pad_numbers_are_jumpers no)
		(fp_rect
			(start -2.0701 0.4826)
			(end 2.0701 -0.4826)
			(stroke
				(width 0)
				(type default)
			)
			(fill no)
			(layer "F.CrtYd")
		)
		(fp_rect
			(start -2.0701 0.4826)
			(end 2.0701 -0.4826)
			(stroke
				(width 0)
				(type default)
			)
			(fill no)
			(layer "F.Fab")
		)
		(pad "1" thru_hole circle
			(at -1.5875 0 180)
			(size 0.508 0.508)
			(drill 0.254)
			(layers "*.Cu" "*.Mask")
			(remove_unused_layers no)
			(net "GND")
			(clearance 0.2286)
			(thermal_gap 0.2286)
		)
		(pad "2" thru_hole circle
			(at -0.5715 0 180)
			(size 0.508 0.508)
			(drill 0.254)
			(layers "*.Cu" "*.Mask")
			(remove_unused_layers no)
			(net "PHY_SCC_B_TO_DRV_B_18_DP")
			(clearance 0.2286)
			(thermal_gap 0.2286)
		)
		(pad "3" thru_hole circle
			(at 0.5715 0 180)
			(size 0.508 0.508)
			(drill 0.254)
			(layers "*.Cu" "*.Mask")
			(remove_unused_layers no)
			(net "PHY_SCC_B_TO_DRV_B_18_DN")
			(clearance 0.2286)
			(thermal_gap 0.2286)
		)
		(pad "4" thru_hole circle
			(at 1.5875 0 180)
			(size 0.508 0.508)
			(drill 0.254)
			(layers "*.Cu" "*.Mask")
			(remove_unused_layers no)
			(net "GND")
			(clearance 0.2286)
			(thermal_gap 0.2286)
		)
	)
	(footprint ""
		(layer "F.Cu")
		(at 141.097 -25.527 90)
		(property "Reference" "C403"
			(at 0 0 90)
			(layer "F.SilkS")
			(hide yes)
			(effects
				(font
					(size 1.27 1.27)
				)
			)
		)
		(property "Value" "SCD033U25V2KX-GP"
			(at 1.1811 -2.7051 90)
			(unlocked yes)
			(layer "F.Fab")
			(hide yes)
			(effects
				(font
					(size 1.016 1.016)
					(thickness 0.1524)
				)
			)
		)
		(property "Device Type" "C402H22"
			(at 1.1811 -4.2291 90)
			(unlocked yes)
			(layer "F.Fab")
			(hide yes)
			(effects
				(font
					(size 1.016 1.016)
					(thickness 0.1524)
				)
			)
		)
		(duplicate_pad_numbers_are_jumpers no)
		(fp_rect
			(start -0.4318 0.9525)
			(end 0.4318 -0.9525)
			(stroke
				(width 0)
				(type default)
			)
			(fill no)
			(layer "F.CrtYd")
		)
		(fp_rect
			(start -0.4318 0.9525)
			(end 0.4318 -0.9525)
			(stroke
				(width 0)
				(type default)
			)
			(fill no)
			(layer "F.Fab")
		)
		(pad "1" smd custom
			(at 0 -0.4445 90)
			(size 0.1524 0.1524)
			(layers "F.Cu" "F.Mask" "F.Paste")
			(net "P12V_B")
			(options
				(clearance outline)
				(anchor circle)
			)
			(primitives
				(gr_poly
					(pts
						(arc
							(start 0.3048 -0.2032)
							(mid 0.275042 -0.275042)
							(end 0.2032 -0.3048)
						)
						(arc
							(start -0.2032 -0.3048)
							(mid -0.275042 -0.275042)
							(end -0.3048 -0.2032)
						)
						(arc
							(start -0.3048 0.2032)
							(mid -0.275042 0.275042)
							(end -0.2032 0.3048)
						)
						(arc
							(start 0.2032 0.3048)
							(mid 0.275042 0.275042)
							(end 0.3048 0.2032)
						)
					)
					(width 0)
					(fill yes)
				)
			)
		)
		(pad "2" smd custom
			(at 0 0.4445 90)
			(size 0.1524 0.1524)
			(layers "F.Cu" "F.Mask" "F.Paste")
			(net "SW_HDD_N28")
			(options
				(clearance outline)
				(anchor circle)
			)
			(primitives
				(gr_poly
					(pts
						(arc
							(start 0.3048 -0.2032)
							(mid 0.275042 -0.275042)
							(end 0.2032 -0.3048)
						)
						(arc
							(start -0.2032 -0.3048)
							(mid -0.275042 -0.275042)
							(end -0.3048 -0.2032)
						)
						(arc
							(start -0.3048 0.2032)
							(mid -0.275042 0.275042)
							(end -0.2032 0.3048)
						)
						(arc
							(start 0.2032 0.3048)
							(mid 0.275042 0.275042)
							(end 0.3048 0.2032)
						)
					)
					(width 0)
					(fill yes)
				)
			)
		)
	)
)
